(kicad_pcb
	(version 20260206)
	(generator "pcbnew")
	(generator_version "10.0")
	(general
		(thickness 1.6)
		(legacy_teardrops no)
	)
	(paper "A4")
	(title_block
		(title "baseboard — 13948-1b.1110WZS1818.brd")
		(comment 1 "Honey Badger (Wiwynn) / footprints 1193-1196 of 2523")
	)
	(layers
		(0 "F.Cu" signal "TOP")
		(4 "In1.Cu" signal "L2GND")
		(6 "In2.Cu" signal "L3")
		(8 "In3.Cu" signal "L4VCC")
		(10 "In4.Cu" signal "L5VCC")
		(12 "In5.Cu" signal "L6")
		(14 "In6.Cu" signal "L7GND")
		(2 "B.Cu" signal "BOTTOM")
		(9 "F.Adhes" user "F.Adhesive")
		(11 "B.Adhes" user "B.Adhesive")
		(13 "F.Paste" user "Package Geometry/Pastemask Top")
		(15 "B.Paste" user "Package Geometry/Pastemask Bottom")
		(5 "F.SilkS" user "Ref Des/Silkscreen Top")
		(7 "B.SilkS" user "Ref Des/Silkscreen Bottom")
		(1 "F.Mask" user "Board Geometry/Soldermask Top")
		(3 "B.Mask" user "Board Geometry/Soldermask Bottom")
		(17 "Dwgs.User" user "User.Drawings")
		(19 "Cmts.User" user "User.Comments")
		(21 "Eco1.User" user "User.Eco1")
		(23 "Eco2.User" user "User.Eco2")
		(25 "Edge.Cuts" user "Board Geometry/Outline")
		(27 "Margin" user)
		(31 "F.CrtYd" user "Package Geometry/Place Bound Top")
		(29 "B.CrtYd" user "Package Geometry/Place Bound Bottom")
		(35 "F.Fab" user "Ref Des/Assembly Top")
		(33 "B.Fab" user "Ref Des/Assembly Bottom")
	)
	(footprint ""
		(layer "F.Cu")
		(at 66.172842 -133.142482 -90)
		(property "Reference" "SU73"
			(at 0 0 270)
			(layer "F.SilkS")
			(hide yes)
			(effects
				(font
					(size 1.27 1.27)
				)
			)
		)
		(property "Value" "S29GL128S10TFIV20-GP"
			(at -0.1778 -20.32 270)
			(unlocked yes)
			(layer "F.Fab")
			(hide yes)
			(effects
				(font
					(size 1.016 1.016)
					(thickness 0.1524)
				)
			)
		)
		(property "Device Type" "TSOP56-1H48"
			(at -0.1778 -22.225 270)
			(unlocked yes)
			(layer "F.Fab")
			(hide yes)
			(effects
				(font
					(size 1.016 1.016)
					(thickness 0.1524)
				)
			)
		)
		(duplicate_pad_numbers_are_jumpers no)
		(fp_line
			(start -7.5438 8.5598)
			(end 6.8326 8.5598)
			(stroke
				(width 0.1524)
				(type default)
			)
			(layer "F.SilkS")
		)
		(fp_line
			(start -7.366 8.5598)
			(end -7.366 10.795)
			(stroke
				(width 0.508)
				(type default)
			)
			(layer "F.SilkS")
		)
		(fp_line
			(start 6.8326 8.5598)
			(end 6.8326 -8.5598)
			(stroke
				(width 0.1524)
				(type default)
			)
			(layer "F.SilkS")
		)
		(fp_line
			(start -7.112 0)
			(end -7.5438 0.4318)
			(stroke
				(width 0.1524)
				(type default)
			)
			(layer "F.SilkS")
		)
		(fp_line
			(start -7.5438 -0.4318)
			(end -7.112 0)
			(stroke
				(width 0.1524)
				(type default)
			)
			(layer "F.SilkS")
		)
		(fp_line
			(start -7.5438 -8.5598)
			(end -7.5438 8.5598)
			(stroke
				(width 0.1524)
				(type default)
			)
			(layer "F.SilkS")
		)
		(fp_line
			(start 6.8326 -8.5598)
			(end -7.5438 -8.5598)
			(stroke
				(width 0.1524)
				(type default)
			)
			(layer "F.SilkS")
		)
		(fp_poly
			(pts
				(xy -7.62 11.049) (xy 7.62 11.049) (xy 7.62 -11.049) (xy -7.62 -11.049)
			)
			(stroke
				(width 0)
				(type default)
			)
			(fill no)
			(layer "F.CrtYd")
		)
		(fp_poly
			(pts
				(xy -7.62 -11.049) (xy 7.62 -11.049) (xy 7.62 11.049) (xy -7.62 11.049)
			)
			(stroke
				(width 0)
				(type default)
			)
			(fill no)
			(layer "F.Fab")
		)
		(pad "1" smd rect
			(at -6.75005 9.6139 270)
			(size 0.3048 1.524)
			(layers "F.Cu" "F.Mask" "F.Paste")
			(net "Net_174")
		)
		(pad "2" smd rect
			(at -6.24967 9.6139 270)
			(size 0.3048 1.524)
			(layers "F.Cu" "F.Mask" "F.Paste")
			(net "EXP_XM_ADDR_23")
		)
		(pad "3" smd rect
			(at -5.75056 9.6139 270)
			(size 0.3048 1.524)
			(layers "F.Cu" "F.Mask" "F.Paste")
			(net "EXP_XM_ADDR_16")
		)
		(pad "4" smd rect
			(at -5.25018 9.6139 270)
			(size 0.3048 1.524)
			(layers "F.Cu" "F.Mask" "F.Paste")
			(net "EXP_XM_ADDR_15")
		)
		(pad "5" smd rect
			(at -4.7498 9.6139 270)
			(size 0.3048 1.524)
			(layers "F.Cu" "F.Mask" "F.Paste")
			(net "EXP_XM_ADDR_14")
		)
		(pad "6" smd rect
			(at -4.24942 9.6139 270)
			(size 0.3048 1.524)
			(layers "F.Cu" "F.Mask" "F.Paste")
			(net "EXP_XM_ADDR_13")
		)
		(pad "7" smd rect
			(at -3.75031 9.6139 270)
			(size 0.3048 1.524)
			(layers "F.Cu" "F.Mask" "F.Paste")
			(net "EXP_XM_ADDR_12")
		)
		(pad "8" smd rect
			(at -3.24993 9.6139 270)
			(size 0.3048 1.524)
			(layers "F.Cu" "F.Mask" "F.Paste")
			(net "EXP_XM_ADDR_11")
		)
		(pad "9" smd rect
			(at -2.74955 9.6139 270)
			(size 0.3048 1.524)
			(layers "F.Cu" "F.Mask" "F.Paste")
			(net "EXP_XM_ADDR_10")
		)
		(pad "10" smd rect
			(at -2.25044 9.6139 270)
			(size 0.3048 1.524)
			(layers "F.Cu" "F.Mask" "F.Paste")
			(net "EXP_XM_ADDR_9")
		)
		(pad "11" smd rect
			(at -1.75006 9.6139 270)
			(size 0.3048 1.524)
			(layers "F.Cu" "F.Mask" "F.Paste")
			(net "EXP_XM_ADDR_20")
		)
		(pad "12" smd rect
			(at -1.24968 9.6139 270)
			(size 0.3048 1.524)
			(layers "F.Cu" "F.Mask" "F.Paste")
			(net "EXP_XM_ADDR_21")
		)
		(pad "13" smd rect
			(at -0.75057 9.6139 270)
			(size 0.3048 1.524)
			(layers "F.Cu" "F.Mask" "F.Paste")
			(net "EXP_XM_WE_N")
		)
		(pad "14" smd rect
			(at -0.25019 9.6139 270)
			(size 0.3048 1.524)
			(layers "F.Cu" "F.Mask" "F.Paste")
			(net "RESET_N")
		)
		(pad "15" smd rect
			(at 0.25019 9.6139 270)
			(size 0.3048 1.524)
			(layers "F.Cu" "F.Mask" "F.Paste")
			(net "EXP_XM_ADDR_22")
		)
		(pad "16" smd rect
			(at 0.75057 9.6139 270)
			(size 0.3048 1.524)
			(layers "F.Cu" "F.Mask" "F.Paste")
			(net "EXP_WP_N")
		)
		(pad "17" smd rect
			(at 1.24968 9.6139 270)
			(size 0.3048 1.524)
			(layers "F.Cu" "F.Mask" "F.Paste")
			(net "EXP_XM_BUSY_N")
		)
		(pad "18" smd rect
			(at 1.75006 9.6139 270)
			(size 0.3048 1.524)
			(layers "F.Cu" "F.Mask" "F.Paste")
			(net "EXP_XM_ADDR_19")
		)
		(pad "19" smd rect
			(at 2.25044 9.6139 270)
			(size 0.3048 1.524)
			(layers "F.Cu" "F.Mask" "F.Paste")
			(net "EXP_XM_ADDR_18")
		)
		(pad "20" smd rect
			(at 2.74955 9.6139 270)
			(size 0.3048 1.524)
			(layers "F.Cu" "F.Mask" "F.Paste")
			(net "EXP_XM_ADDR_8")
		)
		(pad "21" smd rect
			(at 3.24993 9.6139 270)
			(size 0.3048 1.524)
			(layers "F.Cu" "F.Mask" "F.Paste")
			(net "EXP_XM_ADDR_7")
		)
		(pad "22" smd rect
			(at 3.75031 9.6139 270)
			(size 0.3048 1.524)
			(layers "F.Cu" "F.Mask" "F.Paste")
			(net "EXP_XM_ADDR_6")
		)
		(pad "23" smd rect
			(at 4.24942 9.6139 270)
			(size 0.3048 1.524)
			(layers "F.Cu" "F.Mask" "F.Paste")
			(net "EXP_XM_ADDR_5")
		)
		(pad "24" smd rect
			(at 4.7498 9.6139 270)
			(size 0.3048 1.524)
			(layers "F.Cu" "F.Mask" "F.Paste")
			(net "EXP_XM_ADDR_4")
		)
		(pad "25" smd rect
			(at 5.25018 9.6139 270)
			(size 0.3048 1.524)
			(layers "F.Cu" "F.Mask" "F.Paste")
			(net "EXP_XM_ADDR_3")
		)
		(pad "26" smd rect
			(at 5.75056 9.6139 270)
			(size 0.3048 1.524)
			(layers "F.Cu" "F.Mask" "F.Paste")
			(net "EXP_XM_ADDR_2")
		)
		(pad "27" smd rect
			(at 6.24967 9.6139 270)
			(size 0.3048 1.524)
			(layers "F.Cu" "F.Mask" "F.Paste")
			(net "Net_1009")
		)
		(pad "28" smd rect
			(at 6.75005 9.6139 270)
			(size 0.3048 1.524)
			(layers "F.Cu" "F.Mask" "F.Paste")
			(net "Net_1010")
		)
		(pad "29" smd rect
			(at 6.75005 -9.6139 270)
			(size 0.3048 1.524)
			(layers "F.Cu" "F.Mask" "F.Paste")
			(net "P1V8_E")
		)
		(pad "30" smd rect
			(at 6.24967 -9.6139 270)
			(size 0.3048 1.524)
			(layers "F.Cu" "F.Mask" "F.Paste")
			(net "Net_1008")
		)
		(pad "31" smd rect
			(at 5.75056 -9.6139 270)
			(size 0.3048 1.524)
			(layers "F.Cu" "F.Mask" "F.Paste")
			(net "EXP_XM_ADDR_1")
		)
		(pad "32" smd rect
			(at 5.25018 -9.6139 270)
			(size 0.3048 1.524)
			(layers "F.Cu" "F.Mask" "F.Paste")
			(net "EXP_XM_NOR_CS_N")
		)
		(pad "33" smd rect
			(at 4.7498 -9.6139 270)
			(size 0.3048 1.524)
			(layers "F.Cu" "F.Mask" "F.Paste")
			(net "GND")
		)
		(pad "34" smd rect
			(at 4.24942 -9.6139 270)
			(size 0.3048 1.524)
			(layers "F.Cu" "F.Mask" "F.Paste")
			(net "EXP_XM_OE_N")
		)
		(pad "35" smd rect
			(at 3.75031 -9.6139 270)
			(size 0.3048 1.524)
			(layers "F.Cu" "F.Mask" "F.Paste")
			(net "XM_DATA0")
		)
		(pad "36" smd rect
			(at 3.24993 -9.6139 270)
			(size 0.3048 1.524)
			(layers "F.Cu" "F.Mask" "F.Paste")
			(net "XM_DATA8")
		)
		(pad "37" smd rect
			(at 2.74955 -9.6139 270)
			(size 0.3048 1.524)
			(layers "F.Cu" "F.Mask" "F.Paste")
			(net "XM_DATA1")
		)
		(pad "38" smd rect
			(at 2.25044 -9.6139 270)
			(size 0.3048 1.524)
			(layers "F.Cu" "F.Mask" "F.Paste")
			(net "XM_DATA9")
		)
		(pad "39" smd rect
			(at 1.75006 -9.6139 270)
			(size 0.3048 1.524)
			(layers "F.Cu" "F.Mask" "F.Paste")
			(net "XM_DATA2")
		)
		(pad "40" smd rect
			(at 1.24968 -9.6139 270)
			(size 0.3048 1.524)
			(layers "F.Cu" "F.Mask" "F.Paste")
			(net "XM_DATA10")
		)
		(pad "41" smd rect
			(at 0.75057 -9.6139 270)
			(size 0.3048 1.524)
			(layers "F.Cu" "F.Mask" "F.Paste")
			(net "XM_DATA3")
		)
		(pad "42" smd rect
			(at 0.25019 -9.6139 270)
			(size 0.3048 1.524)
			(layers "F.Cu" "F.Mask" "F.Paste")
			(net "XM_DATA11")
		)
		(pad "43" smd rect
			(at -0.25019 -9.6139 270)
			(size 0.3048 1.524)
			(layers "F.Cu" "F.Mask" "F.Paste")
			(net "P3V3_STBY")
		)
		(pad "44" smd rect
			(at -0.75057 -9.6139 270)
			(size 0.3048 1.524)
			(layers "F.Cu" "F.Mask" "F.Paste")
			(net "XM_DATA4")
		)
		(pad "45" smd rect
			(at -1.24968 -9.6139 270)
			(size 0.3048 1.524)
			(layers "F.Cu" "F.Mask" "F.Paste")
			(net "XM_DATA12")
		)
		(pad "46" smd rect
			(at -1.75006 -9.6139 270)
			(size 0.3048 1.524)
			(layers "F.Cu" "F.Mask" "F.Paste")
			(net "XM_DATA5")
		)
		(pad "47" smd rect
			(at -2.25044 -9.6139 270)
			(size 0.3048 1.524)
			(layers "F.Cu" "F.Mask" "F.Paste")
			(net "XM_DATA13")
		)
		(pad "48" smd rect
			(at -2.74955 -9.6139 270)
			(size 0.3048 1.524)
			(layers "F.Cu" "F.Mask" "F.Paste")
			(net "XM_DATA6")
		)
		(pad "49" smd rect
			(at -3.24993 -9.6139 270)
			(size 0.3048 1.524)
			(layers "F.Cu" "F.Mask" "F.Paste")
			(net "XM_DATA14")
		)
		(pad "50" smd rect
			(at -3.75031 -9.6139 270)
			(size 0.3048 1.524)
			(layers "F.Cu" "F.Mask" "F.Paste")
			(net "XM_DATA7")
		)
		(pad "51" smd rect
			(at -4.24942 -9.6139 270)
			(size 0.3048 1.524)
			(layers "F.Cu" "F.Mask" "F.Paste")
			(net "XM_DATA15")
		)
		(pad "52" smd rect
			(at -4.7498 -9.6139 270)
			(size 0.3048 1.524)
			(layers "F.Cu" "F.Mask" "F.Paste")
			(net "GND")
		)
		(pad "53" smd rect
			(at -5.25018 -9.6139 270)
			(size 0.3048 1.524)
			(layers "F.Cu" "F.Mask" "F.Paste")
			(net "Net_261")
		)
		(pad "54" smd rect
			(at -5.75056 -9.6139 270)
			(size 0.3048 1.524)
			(layers "F.Cu" "F.Mask" "F.Paste")
			(net "EXP_XM_ADDR_17")
		)
		(pad "55" smd rect
			(at -6.24967 -9.6139 270)
			(size 0.3048 1.524)
			(layers "F.Cu" "F.Mask" "F.Paste")
			(net "Net_1011")
		)
		(pad "56" smd rect
			(at -6.75005 -9.6139 270)
			(size 0.3048 1.524)
			(layers "F.Cu" "F.Mask" "F.Paste")
			(net "Net_173")
		)
	)
	(footprint ""
		(layer "F.Cu")
		(at 97.917 -10.5156 180)
		(property "Reference" "SL8"
			(at 0 0 180)
			(layer "F.SilkS")
			(hide yes)
			(effects
				(font
					(size 1.27 1.27)
				)
			)
		)
		(property "Value" "MPZ2012S300AT-GP"
			(at 0 -4.2418 180)
			(unlocked yes)
			(layer "F.Fab")
			(hide yes)
			(effects
				(font
					(size 1.016 1.016)
					(thickness 0.1524)
				)
			)
		)
		(property "Device Type" "L805H42"
			(at 0 -5.7912 180)
			(unlocked yes)
			(layer "F.Fab")
			(hide yes)
			(effects
				(font
					(size 1.016 1.016)
					(thickness 0.1524)
				)
			)
		)
		(duplicate_pad_numbers_are_jumpers no)
		(fp_line
			(start 0.889 1.7018)
			(end -0.889 1.7018)
			(stroke
				(width 0.1524)
				(type default)
			)
			(layer "F.SilkS")
		)
		(fp_line
			(start 0.889 -1.7018)
			(end 0.889 1.7018)
			(stroke
				(width 0.1524)
				(type default)
			)
			(layer "F.SilkS")
		)
		(fp_line
			(start -0.889 1.7018)
			(end -0.889 -1.7018)
			(stroke
				(width 0.1524)
				(type default)
			)
			(layer "F.SilkS")
		)
		(fp_line
			(start -0.889 -1.7018)
			(end 0.889 -1.7018)
			(stroke
				(width 0.1524)
				(type default)
			)
			(layer "F.SilkS")
		)
		(fp_rect
			(start -0.9652 1.778)
			(end 0.9652 -1.778)
			(stroke
				(width 0)
				(type default)
			)
			(fill no)
			(layer "F.CrtYd")
		)
		(fp_rect
			(start -0.9652 1.778)
			(end 0.9652 -1.778)
			(stroke
				(width 0)
				(type default)
			)
			(fill no)
			(layer "F.Fab")
		)
		(pad "1" smd rect
			(at 0 -0.9652 180)
			(size 1.397 1.143)
			(layers "F.Cu" "F.Mask" "F.Paste")
			(net "P0V955_C")
		)
		(pad "2" smd rect
			(at 0 0.9652 180)
			(size 1.397 1.143)
			(layers "F.Cu" "F.Mask" "F.Paste")
			(net "PCE_AVDD")
		)
	)
	(footprint ""
		(layer "F.Cu")
		(at 273.041872 -190.927736)
		(property "Reference" "R300"
			(at 0 0 0)
			(layer "F.SilkS")
			(hide yes)
			(effects
				(font
					(size 1.27 1.27)
				)
			)
		)
		(property "Value" "0R2J-2-GP"
			(at 0.064008 -3.993896 0)
			(unlocked yes)
			(layer "F.Fab")
			(hide yes)
			(effects
				(font
					(size 1.016 1.016)
					(thickness 0.1524)
				)
			)
		)
		(property "Device Type" "R402H16"
			(at 0.064008 -5.517896 0)
			(unlocked yes)
			(layer "F.Fab")
			(hide yes)
			(effects
				(font
					(size 1.016 1.016)
					(thickness 0.1524)
				)
			)
		)
		(duplicate_pad_numbers_are_jumpers no)
		(fp_line
			(start -0.508 -0.9398)
			(end -0.508 0.9398)
			(stroke
				(width 0.1524)
				(type default)
			)
			(layer "F.SilkS")
		)
		(fp_line
			(start 0.508 -0.9398)
			(end -0.508 -0.9398)
			(stroke
				(width 0.1524)
				(type default)
			)
			(layer "F.SilkS")
		)
		(fp_rect
			(start -0.508 0.9398)
			(end 0.508 -0.9398)
			(stroke
				(width 0)
				(type default)
			)
			(fill no)
			(layer "F.CrtYd")
		)
		(fp_rect
			(start -0.508 0.9398)
			(end 0.508 -0.9398)
			(stroke
				(width 0)
				(type default)
			)
			(fill no)
			(layer "F.Fab")
		)
		(pad "1" smd custom
			(at 0 -0.4445)
			(size 0.1397 0.1397)
			(layers "F.Cu" "F.Mask" "F.Paste")
			(net "P1V8_STBY_PG")
			(options
				(clearance outline)
				(anchor circle)
			)
			(primitives
				(gr_poly
					(pts
						(arc
							(start -0.1778 -0.2794)
							(mid -0.249642 -0.249642)
							(end -0.2794 -0.1778)
						)
						(arc
							(start -0.2794 0.1778)
							(mid -0.249642 0.249642)
							(end -0.1778 0.2794)
						)
						(arc
							(start 0.1778 0.2794)
							(mid 0.249642 0.249642)
							(end 0.2794 0.1778)
						)
						(arc
							(start 0.2794 -0.1778)
							(mid 0.249642 -0.249642)
							(end 0.1778 -0.2794)
						)
					)
					(width 0)
					(fill yes)
				)
			)
		)
		(pad "2" smd custom
			(at 0 0.4445)
			(size 0.1397 0.1397)
			(layers "F.Cu" "F.Mask" "F.Paste")
			(net "BMC0_SRST_N")
			(options
				(clearance outline)
				(anchor circle)
			)
			(primitives
				(gr_poly
					(pts
						(arc
							(start -0.1778 -0.2794)
							(mid -0.249642 -0.249642)
							(end -0.2794 -0.1778)
						)
						(arc
							(start -0.2794 0.1778)
							(mid -0.249642 0.249642)
							(end -0.1778 0.2794)
						)
						(arc
							(start 0.1778 0.2794)
							(mid 0.249642 0.249642)
							(end 0.2794 0.1778)
						)
						(arc
							(start 0.2794 -0.1778)
							(mid 0.249642 -0.249642)
							(end 0.1778 -0.2794)
						)
					)
					(width 0)
					(fill yes)
				)
			)
		)
	)
	(footprint ""
		(layer "F.Cu")
		(at 57.15 -225.806)
		(property "Reference" "R2119"
			(at 0 0 0)
			(layer "F.SilkS")
			(hide yes)
			(effects
				(font
					(size 1.27 1.27)
				)
			)
		)
		(property "Value" "10R2F-L-GP"
			(at 0.064008 -3.993896 0)
			(unlocked yes)
			(layer "F.Fab")
			(hide yes)
			(effects
				(font
					(size 1.016 1.016)
					(thickness 0.1524)
				)
			)
		)
		(property "Device Type" "R402H14"
			(at 0.064008 -5.517896 0)
			(unlocked yes)
			(layer "F.Fab")
			(hide yes)
			(effects
				(font
					(size 1.016 1.016)
					(thickness 0.1524)
				)
			)
		)
		(duplicate_pad_numbers_are_jumpers no)
		(fp_line
			(start -0.508 -0.9398)
			(end -0.508 0.9398)
			(stroke
				(width 0.1524)
				(type default)
			)
			(layer "F.SilkS")
		)
		(fp_line
			(start 0.508 -0.9398)
			(end -0.508 -0.9398)
			(stroke
				(width 0.1524)
				(type default)
			)
			(layer "F.SilkS")
		)
		(fp_rect
			(start -0.508 0.9398)
			(end 0.508 -0.9398)
			(stroke
				(width 0)
				(type default)
			)
			(fill no)
			(layer "F.CrtYd")
		)
		(fp_rect
			(start -0.508 0.9398)
			(end 0.508 -0.9398)
			(stroke
				(width 0)
				(type default)
			)
			(fill no)
			(layer "F.Fab")
		)
		(pad "1" smd custom
			(at 0 -0.4445)
			(size 0.1397 0.1397)
			(layers "F.Cu" "F.Mask" "F.Paste")
			(net "MB0_CM_SENSE_R1_P")
			(options
				(clearance outline)
				(anchor circle)
			)
			(primitives
				(gr_poly
					(pts
						(arc
							(start -0.1778 -0.2794)
							(mid -0.249642 -0.249642)
							(end -0.2794 -0.1778)
						)
						(arc
							(start -0.2794 0.1778)
							(mid -0.249642 0.249642)
							(end -0.1778 0.2794)
						)
						(arc
							(start 0.1778 0.2794)
							(mid 0.249642 0.249642)
							(end 0.2794 0.1778)
						)
						(arc
							(start 0.2794 -0.1778)
							(mid 0.249642 -0.249642)
							(end 0.1778 -0.2794)
						)
					)
					(width 0)
					(fill yes)
				)
			)
		)
		(pad "2" smd custom
			(at 0 0.4445)
			(size 0.1397 0.1397)
			(layers "F.Cu" "F.Mask" "F.Paste")
			(net "MB0_CM_SENSE_P")
			(options
				(clearance outline)
				(anchor circle)
			)
			(primitives
				(gr_poly
					(pts
						(arc
							(start -0.1778 -0.2794)
							(mid -0.249642 -0.249642)
							(end -0.2794 -0.1778)
						)
						(arc
							(start -0.2794 0.1778)
							(mid -0.249642 0.249642)
							(end -0.1778 0.2794)
						)
						(arc
							(start 0.1778 0.2794)
							(mid 0.249642 0.249642)
							(end 0.2794 0.1778)
						)
						(arc
							(start 0.2794 -0.1778)
							(mid 0.249642 -0.249642)
							(end 0.1778 -0.2794)
						)
					)
					(width 0)
					(fill yes)
				)
			)
		)
	)
)
